(kicad_pcb
	(version 20260206)
	(generator "pcbnew")
	(generator_version "10.0")
	(general
		(thickness 1.6)
		(legacy_teardrops no)
	)
	(paper "A4")
	(title_block
		(title "Wiwynn_Tioga_Pass_MB.brd")
		(comment 1 "Tioga Pass / footprints 152-152 of 4770")
	)
	(layers
		(0 "F.Cu" signal "TOP")
		(4 "In1.Cu" signal "L2GND")
		(6 "In2.Cu" signal "L3")
		(8 "In3.Cu" signal "L4GND")
		(10 "In4.Cu" signal "L5")
		(12 "In5.Cu" signal "L6GND")
		(14 "In6.Cu" signal "L7VCC")
		(16 "In7.Cu" signal "L8VCC")
		(18 "In8.Cu" signal "L9GND")
		(20 "In9.Cu" signal "L10")
		(22 "In10.Cu" signal "L11GND")
		(24 "In11.Cu" signal "L12")
		(26 "In12.Cu" signal "L13GND")
		(2 "B.Cu" signal "BOTTOM")
		(9 "F.Adhes" user "F.Adhesive")
		(11 "B.Adhes" user "B.Adhesive")
		(13 "F.Paste" user "Package Geometry/Pastemask Top")
		(15 "B.Paste" user "Package Geometry/Pastemask Bottom")
		(5 "F.SilkS" user "Ref Des/Silkscreen Top")
		(7 "B.SilkS" user "Ref Des/Silkscreen Bottom")
		(1 "F.Mask" user "Board Geometry/Soldermask Top")
		(3 "B.Mask" user "Board Geometry/Soldermask Bottom")
		(17 "Dwgs.User" user "User.Drawings")
		(19 "Cmts.User" user "User.Comments")
		(21 "Eco1.User" user "User.Eco1")
		(23 "Eco2.User" user "User.Eco2")
		(25 "Edge.Cuts" user "Board Geometry/Outline")
		(27 "Margin" user)
		(31 "F.CrtYd" user "Package Geometry/Place Bound Top")
		(29 "B.CrtYd" user "Package Geometry/Place Bound Bottom")
		(35 "F.Fab" user "Ref Des/Assembly Top")
		(33 "B.Fab" user "Ref Des/Assembly Bottom")
	)
	(footprint ""
		(layer "F.Cu")
		(at 273.558 -69.977)
		(property "Reference" "R5D6"
			(at 0 0 0)
			(layer "F.SilkS")
			(hide yes)
			(effects
				(font
					(size 1.27 1.27)
				)
			)
		)
		(property "Value" ""
			(at 0 0 0)
			(layer "F.Fab")
			(effects
				(font
					(size 1.27 1.27)
				)
			)
		)
		(duplicate_pad_numbers_are_jumpers no)
		(fp_poly
			(pts
				(xy -0.2794 -0.1016) (xy 0.2794 -0.1016) (xy 0.2794 0.9906) (xy -0.2794 0.9906)
			)
			(stroke
				(width 0)
				(type default)
			)
			(fill no)
			(layer "F.CrtYd")
		)
		(fp_line
			(start -0.2794 -0.1016)
			(end -0.2794 0.9906)
			(stroke
				(width 0.1)
				(type default)
			)
			(layer "F.Fab")
		)
		(fp_line
			(start -0.2794 0.9906)
			(end 0.2794 0.9906)
			(stroke
				(width 0.1)
				(type default)
			)
			(layer "F.Fab")
		)
		(fp_line
			(start 0.2794 -0.1016)
			(end -0.2794 -0.1016)
			(stroke
				(width 0.1)
				(type default)
			)
			(layer "F.Fab")
		)
		(fp_line
			(start 0.2794 0.9906)
			(end 0.2794 -0.1016)
			(stroke
				(width 0.1)
				(type default)
			)
			(layer "F.Fab")
		)
		(pad "1" smd rect
			(at 0 0)
			(size 0.508 0.508)
			(layers "F.Cu" "F.Mask" "F.Paste")
			(net "PVCCIO_CPU0")
		)
		(pad "2" smd rect
			(at 0 0.889)
			(size 0.508 0.508)
			(layers "F.Cu" "F.Mask" "F.Paste")
			(net "VSENSE_PMAX_CPU0")
		)
		(zone
			(layer "F.Cu")
			(hatch none 0.5)
			(connect_pads
				(clearance 0)
			)
			(min_thickness 0.25)
			(keepout
				(tracks allowed)
				(vias not_allowed)
				(pads allowed)
				(copperpour not_allowed)
				(footprints allowed)
			)
			(placement
				(enabled no)
				(sheetname "")
			)
			(fill
				(thermal_gap 0.5)
				(thermal_bridge_width 0.5)
				(island_removal_mode 0)
			)
			(polygon
				(pts
					(xy 273.304 -69.723) (xy 273.812 -69.723) (xy 273.812 -69.342) (xy 273.304 -69.342)
				)
			)
		)
		(zone
			(layer "F.Cu")
			(hatch none 0.5)
			(connect_pads
				(clearance 0)
			)
			(min_thickness 0.25)
			(keepout
				(tracks not_allowed)
				(vias allowed)
				(pads allowed)
				(copperpour not_allowed)
				(footprints allowed)
			)
			(placement
				(enabled no)
				(sheetname "")
			)
			(fill
				(thermal_gap 0.5)
				(thermal_bridge_width 0.5)
				(island_removal_mode 0)
			)
			(polygon
				(pts
					(xy 273.304 -69.342) (xy 273.812 -69.342) (xy 273.812 -69.723) (xy 273.304 -69.723)
				)
			)
		)
	)
)
